(kicad_pcb
	(version 20260206)
	(generator "pcbnew")
	(generator_version "10.0")
	(general
		(thickness 1.6)
		(legacy_teardrops no)
	)
	(paper "A4")
	(title_block
		(title "01162023_DA0F0TEBIF0_F0T_Expander_BD_F_brd_V02_OCP.brd")
		(comment 1 "Grand Teton / footprint 6619 of 9728 (PEX0), pads 1421-1534 of 2397")
	)
	(layers
		(0 "F.Cu" signal "TOP")
		(4 "In1.Cu" signal "GND")
		(6 "In2.Cu" signal "VCC")
		(8 "In3.Cu" signal "VCC1")
		(10 "In4.Cu" signal "GND1")
		(12 "In5.Cu" signal "IN1")
		(14 "In6.Cu" signal "GND2")
		(16 "In7.Cu" signal "IN2")
		(18 "In8.Cu" signal "GND3")
		(20 "In9.Cu" signal "IN3")
		(22 "In10.Cu" signal "GND4")
		(24 "In11.Cu" signal "IN4")
		(26 "In12.Cu" signal "GND5")
		(28 "In13.Cu" signal "IN5")
		(30 "In14.Cu" signal "GND6")
		(32 "In15.Cu" signal "IN6")
		(34 "In16.Cu" signal "GND7")
		(2 "B.Cu" signal "BOTTOM")
		(9 "F.Adhes" user "F.Adhesive")
		(11 "B.Adhes" user "B.Adhesive")
		(13 "F.Paste" user "Package Geometry/Pastemask Top")
		(15 "B.Paste" user "Package Geometry/Pastemask Bottom")
		(5 "F.SilkS" user "Ref Des/Silkscreen Top")
		(7 "B.SilkS" user "Ref Des/Silkscreen Bottom")
		(1 "F.Mask" user "Board Geometry/Soldermask Top")
		(3 "B.Mask" user "Board Geometry/Soldermask Bottom")
		(17 "Dwgs.User" user "User.Drawings")
		(19 "Cmts.User" user "User.Comments")
		(21 "Eco1.User" user "User.Eco1")
		(23 "Eco2.User" user "User.Eco2")
		(25 "Edge.Cuts" user "Board Geometry/Outline")
		(27 "Margin" user)
		(31 "F.CrtYd" user "Package Geometry/Place Bound Top")
		(29 "B.CrtYd" user "Package Geometry/Place Bound Bottom")
		(35 "F.Fab" user "Ref Des/Assembly Top")
		(33 "B.Fab" user "Ref Des/Assembly Bottom")
	)
	(footprint ""
		(layer "F.Cu")
		(at 59.649868 -295.89984)
		(property "Reference" "PEX0"
			(at -3.360166 35.566858 0)
			(unlocked yes)
			(layer "F.SilkS")
			(effects
				(font
					(size 2.032 1.524)
					(thickness 0.1524)
				)
				(justify left)
			)
		)
		(property "Value" ""
			(at 0 0 0)
			(layer "F.Fab")
			(effects
				(font
					(size 1.27 1.27)
				)
			)
		)
		(duplicate_pad_numbers_are_jumpers no)
		(pad "BH2" smd circle
			(at -21.850096 21.850096)
			(size 0.4572 0.4572)
			(layers "F.Cu" "F.Mask" "F.Paste")
			(net "GND")
		)
		(pad "BH3" smd circle
			(at -20.899882 21.850096)
			(size 0.4572 0.4572)
			(layers "F.Cu" "F.Mask" "F.Paste")
			(net "Net_2732")
		)
		(pad "BH4" smd circle
			(at -19.949922 21.850096)
			(size 0.4572 0.4572)
			(layers "F.Cu" "F.Mask" "F.Paste")
			(net "GND")
		)
		(pad "BH5" smd circle
			(at -18.999962 21.850096)
			(size 0.4572 0.4572)
			(layers "F.Cu" "F.Mask" "F.Paste")
			(net "Net_2734")
		)
		(pad "BH6" smd circle
			(at -18.050002 21.850096)
			(size 0.4572 0.4572)
			(layers "F.Cu" "F.Mask" "F.Paste")
			(net "GND")
		)
		(pad "BH7" smd circle
			(at -17.100042 21.850096)
			(size 0.4572 0.4572)
			(layers "F.Cu" "F.Mask" "F.Paste")
			(net "Net_2736")
		)
		(pad "BH8" smd circle
			(at -16.150082 21.850096)
			(size 0.4572 0.4572)
			(layers "F.Cu" "F.Mask" "F.Paste")
			(net "GND")
		)
		(pad "BH9" smd circle
			(at -15.200122 21.850096)
			(size 0.4572 0.4572)
			(layers "F.Cu" "F.Mask" "F.Paste")
			(net "P5E_PEX0_STN2_RX_DP<47>")
		)
		(pad "BH10" smd circle
			(at -14.249908 21.850096)
			(size 0.4572 0.4572)
			(layers "F.Cu" "F.Mask" "F.Paste")
			(net "GND")
		)
		(pad "BH11" smd circle
			(at -13.299948 21.850096)
			(size 0.4572 0.4572)
			(layers "F.Cu" "F.Mask" "F.Paste")
			(net "P5E_PEX0_STN2_RX_DP<45>")
		)
		(pad "BH12" smd circle
			(at -12.349988 21.850096)
			(size 0.4572 0.4572)
			(layers "F.Cu" "F.Mask" "F.Paste")
			(net "GND")
		)
		(pad "BH13" smd circle
			(at -11.400028 21.850096)
			(size 0.4572 0.4572)
			(layers "F.Cu" "F.Mask" "F.Paste")
			(net "P5E_PEX0_STN2_RX_DP<43>")
		)
		(pad "BH14" smd circle
			(at -10.450068 21.850096)
			(size 0.4572 0.4572)
			(layers "F.Cu" "F.Mask" "F.Paste")
			(net "GND")
		)
		(pad "BH15" smd circle
			(at -9.500108 21.850096)
			(size 0.4572 0.4572)
			(layers "F.Cu" "F.Mask" "F.Paste")
			(net "P5E_PEX0_STN2_RX_DP<41>")
		)
		(pad "BH16" smd circle
			(at -8.549894 21.850096)
			(size 0.4572 0.4572)
			(layers "F.Cu" "F.Mask" "F.Paste")
			(net "GND")
		)
		(pad "BH17" smd circle
			(at -7.599934 21.850096)
			(size 0.4572 0.4572)
			(layers "F.Cu" "F.Mask" "F.Paste")
			(net "P5E_PEX0_STN2_RX_DP<39>")
		)
		(pad "BH18" smd circle
			(at -6.649974 21.850096)
			(size 0.4572 0.4572)
			(layers "F.Cu" "F.Mask" "F.Paste")
			(net "GND")
		)
		(pad "BH19" smd circle
			(at -5.700014 21.850096)
			(size 0.4572 0.4572)
			(layers "F.Cu" "F.Mask" "F.Paste")
			(net "P5E_PEX0_STN2_RX_DP<37>")
		)
		(pad "BH20" smd circle
			(at -4.750054 21.850096)
			(size 0.4572 0.4572)
			(layers "F.Cu" "F.Mask" "F.Paste")
			(net "GND")
		)
		(pad "BH21" smd circle
			(at -3.800094 21.850096)
			(size 0.4572 0.4572)
			(layers "F.Cu" "F.Mask" "F.Paste")
			(net "P5E_PEX0_STN2_RX_DP<35>")
		)
		(pad "BH22" smd circle
			(at -2.84988 21.850096)
			(size 0.4572 0.4572)
			(layers "F.Cu" "F.Mask" "F.Paste")
			(net "GND")
		)
		(pad "BH23" smd circle
			(at -1.89992 21.850096)
			(size 0.4572 0.4572)
			(layers "F.Cu" "F.Mask" "F.Paste")
			(net "P5E_PEX0_STN2_RX_DP<33>")
		)
		(pad "BH24" smd circle
			(at -0.94996 21.850096)
			(size 0.4572 0.4572)
			(layers "F.Cu" "F.Mask" "F.Paste")
			(net "GND")
		)
		(pad "BH25" smd circle
			(at 0 21.850096)
			(size 0.4572 0.4572)
			(layers "F.Cu" "F.Mask" "F.Paste")
			(net "P5E_PEX0_STN1_RX_DP<16>")
		)
		(pad "BH26" smd circle
			(at 0.94996 21.850096)
			(size 0.4572 0.4572)
			(layers "F.Cu" "F.Mask" "F.Paste")
			(net "GND")
		)
		(pad "BH27" smd circle
			(at 1.89992 21.850096)
			(size 0.4572 0.4572)
			(layers "F.Cu" "F.Mask" "F.Paste")
			(net "P5E_PEX0_STN1_RX_DP<18>")
		)
		(pad "BH28" smd circle
			(at 2.84988 21.850096)
			(size 0.4572 0.4572)
			(layers "F.Cu" "F.Mask" "F.Paste")
			(net "GND")
		)
		(pad "BH29" smd circle
			(at 3.800094 21.850096)
			(size 0.4572 0.4572)
			(layers "F.Cu" "F.Mask" "F.Paste")
			(net "P5E_PEX0_STN1_RX_DP<20>")
		)
		(pad "BH30" smd circle
			(at 4.750054 21.850096)
			(size 0.4572 0.4572)
			(layers "F.Cu" "F.Mask" "F.Paste")
			(net "GND")
		)
		(pad "BH31" smd circle
			(at 5.700014 21.850096)
			(size 0.4572 0.4572)
			(layers "F.Cu" "F.Mask" "F.Paste")
			(net "P5E_PEX0_STN1_RX_DP<22>")
		)
		(pad "BH32" smd circle
			(at 6.649974 21.850096)
			(size 0.4572 0.4572)
			(layers "F.Cu" "F.Mask" "F.Paste")
			(net "GND")
		)
		(pad "BH33" smd circle
			(at 7.599934 21.850096)
			(size 0.4572 0.4572)
			(layers "F.Cu" "F.Mask" "F.Paste")
			(net "P5E_PEX0_STN1_RX_DP<24>")
		)
		(pad "BH34" smd circle
			(at 8.549894 21.850096)
			(size 0.4572 0.4572)
			(layers "F.Cu" "F.Mask" "F.Paste")
			(net "GND")
		)
		(pad "BH35" smd circle
			(at 9.500108 21.850096)
			(size 0.4572 0.4572)
			(layers "F.Cu" "F.Mask" "F.Paste")
			(net "P5E_PEX0_STN1_RX_DP<26>")
		)
		(pad "BH36" smd circle
			(at 10.450068 21.850096)
			(size 0.4572 0.4572)
			(layers "F.Cu" "F.Mask" "F.Paste")
			(net "GND")
		)
		(pad "BH37" smd circle
			(at 11.400028 21.850096)
			(size 0.4572 0.4572)
			(layers "F.Cu" "F.Mask" "F.Paste")
			(net "P5E_PEX0_STN1_RX_DP<28>")
		)
		(pad "BH38" smd circle
			(at 12.349988 21.850096)
			(size 0.4572 0.4572)
			(layers "F.Cu" "F.Mask" "F.Paste")
			(net "GND")
		)
		(pad "BH39" smd circle
			(at 13.299948 21.850096)
			(size 0.4572 0.4572)
			(layers "F.Cu" "F.Mask" "F.Paste")
			(net "P5E_PEX0_STN1_RX_DP<30>")
		)
		(pad "BH40" smd circle
			(at 14.249908 21.850096)
			(size 0.4572 0.4572)
			(layers "F.Cu" "F.Mask" "F.Paste")
			(net "GND")
		)
		(pad "BH41" smd circle
			(at 15.200122 21.850096)
			(size 0.4572 0.4572)
			(layers "F.Cu" "F.Mask" "F.Paste")
			(net "P5E_PEX0_STN0_RX_DP<15>")
		)
		(pad "BH42" smd circle
			(at 16.150082 21.850096)
			(size 0.4572 0.4572)
			(layers "F.Cu" "F.Mask" "F.Paste")
			(net "GND")
		)
		(pad "BH43" smd circle
			(at 17.100042 21.850096)
			(size 0.4572 0.4572)
			(layers "F.Cu" "F.Mask" "F.Paste")
			(net "P5E_PEX0_STN0_RX_DP<13>")
		)
		(pad "BH44" smd circle
			(at 18.050002 21.850096)
			(size 0.4572 0.4572)
			(layers "F.Cu" "F.Mask" "F.Paste")
			(net "GND")
		)
		(pad "BH45" smd circle
			(at 18.999962 21.850096)
			(size 0.4572 0.4572)
			(layers "F.Cu" "F.Mask" "F.Paste")
			(net "P5E_PEX0_STN0_RX_DP<11>")
		)
		(pad "BH46" smd circle
			(at 19.949922 21.850096)
			(size 0.4572 0.4572)
			(layers "F.Cu" "F.Mask" "F.Paste")
			(net "GND")
		)
		(pad "BH47" smd circle
			(at 20.899882 21.850096)
			(size 0.4572 0.4572)
			(layers "F.Cu" "F.Mask" "F.Paste")
			(net "P5E_PEX0_STN0_RX_DP<9>")
		)
		(pad "BH48" smd circle
			(at 21.850096 21.850096)
			(size 0.4572 0.4572)
			(layers "F.Cu" "F.Mask" "F.Paste")
			(net "GND")
		)
		(pad "BH49" smd circle
			(at 22.800056 21.850096)
			(size 0.4572 0.4572)
			(layers "F.Cu" "F.Mask" "F.Paste")
			(net "GND")
		)
		(pad "BJ2" smd circle
			(at -21.850096 22.800056)
			(size 0.4572 0.4572)
			(layers "F.Cu" "F.Mask" "F.Paste")
			(net "GND")
		)
		(pad "BJ3" smd circle
			(at -20.899882 22.800056)
			(size 0.4572 0.4572)
			(layers "F.Cu" "F.Mask" "F.Paste")
			(net "Net_2718")
		)
		(pad "BJ4" smd circle
			(at -19.949922 22.800056)
			(size 0.4572 0.4572)
			(layers "F.Cu" "F.Mask" "F.Paste")
			(net "GND")
		)
		(pad "BJ5" smd circle
			(at -18.999962 22.800056)
			(size 0.4572 0.4572)
			(layers "F.Cu" "F.Mask" "F.Paste")
			(net "Net_2720")
		)
		(pad "BJ6" smd circle
			(at -18.050002 22.800056)
			(size 0.4572 0.4572)
			(layers "F.Cu" "F.Mask" "F.Paste")
			(net "GND")
		)
		(pad "BJ7" smd circle
			(at -17.100042 22.800056)
			(size 0.4572 0.4572)
			(layers "F.Cu" "F.Mask" "F.Paste")
			(net "Net_2722")
		)
		(pad "BJ8" smd circle
			(at -16.150082 22.800056)
			(size 0.4572 0.4572)
			(layers "F.Cu" "F.Mask" "F.Paste")
			(net "GND")
		)
		(pad "BJ9" smd circle
			(at -15.200122 22.800056)
			(size 0.4572 0.4572)
			(layers "F.Cu" "F.Mask" "F.Paste")
			(net "P5E_PEX0_STN2_RX_DN<47>")
		)
		(pad "BJ10" smd circle
			(at -14.249908 22.800056)
			(size 0.4572 0.4572)
			(layers "F.Cu" "F.Mask" "F.Paste")
			(net "GND")
		)
		(pad "BJ11" smd circle
			(at -13.299948 22.800056)
			(size 0.4572 0.4572)
			(layers "F.Cu" "F.Mask" "F.Paste")
			(net "P5E_PEX0_STN2_RX_DN<45>")
		)
		(pad "BJ12" smd circle
			(at -12.349988 22.800056)
			(size 0.4572 0.4572)
			(layers "F.Cu" "F.Mask" "F.Paste")
			(net "GND")
		)
		(pad "BJ13" smd circle
			(at -11.400028 22.800056)
			(size 0.4572 0.4572)
			(layers "F.Cu" "F.Mask" "F.Paste")
			(net "P5E_PEX0_STN2_RX_DN<43>")
		)
		(pad "BJ14" smd circle
			(at -10.450068 22.800056)
			(size 0.4572 0.4572)
			(layers "F.Cu" "F.Mask" "F.Paste")
			(net "GND")
		)
		(pad "BJ15" smd circle
			(at -9.500108 22.800056)
			(size 0.4572 0.4572)
			(layers "F.Cu" "F.Mask" "F.Paste")
			(net "P5E_PEX0_STN2_RX_DN<41>")
		)
		(pad "BJ16" smd circle
			(at -8.549894 22.800056)
			(size 0.4572 0.4572)
			(layers "F.Cu" "F.Mask" "F.Paste")
			(net "GND")
		)
		(pad "BJ17" smd circle
			(at -7.599934 22.800056)
			(size 0.4572 0.4572)
			(layers "F.Cu" "F.Mask" "F.Paste")
			(net "P5E_PEX0_STN2_RX_DN<39>")
		)
		(pad "BJ18" smd circle
			(at -6.649974 22.800056)
			(size 0.4572 0.4572)
			(layers "F.Cu" "F.Mask" "F.Paste")
			(net "GND")
		)
		(pad "BJ19" smd circle
			(at -5.700014 22.800056)
			(size 0.4572 0.4572)
			(layers "F.Cu" "F.Mask" "F.Paste")
			(net "P5E_PEX0_STN2_RX_DN<37>")
		)
		(pad "BJ20" smd circle
			(at -4.750054 22.800056)
			(size 0.4572 0.4572)
			(layers "F.Cu" "F.Mask" "F.Paste")
			(net "GND")
		)
		(pad "BJ21" smd circle
			(at -3.800094 22.800056)
			(size 0.4572 0.4572)
			(layers "F.Cu" "F.Mask" "F.Paste")
			(net "P5E_PEX0_STN2_RX_DN<35>")
		)
		(pad "BJ22" smd circle
			(at -2.84988 22.800056)
			(size 0.4572 0.4572)
			(layers "F.Cu" "F.Mask" "F.Paste")
			(net "GND")
		)
		(pad "BJ23" smd circle
			(at -1.89992 22.800056)
			(size 0.4572 0.4572)
			(layers "F.Cu" "F.Mask" "F.Paste")
			(net "P5E_PEX0_STN2_RX_DN<33>")
		)
		(pad "BJ24" smd circle
			(at -0.94996 22.800056)
			(size 0.4572 0.4572)
			(layers "F.Cu" "F.Mask" "F.Paste")
			(net "GND")
		)
		(pad "BJ25" smd circle
			(at 0 22.800056)
			(size 0.4572 0.4572)
			(layers "F.Cu" "F.Mask" "F.Paste")
			(net "P5E_PEX0_STN1_RX_DN<16>")
		)
		(pad "BJ26" smd circle
			(at 0.94996 22.800056)
			(size 0.4572 0.4572)
			(layers "F.Cu" "F.Mask" "F.Paste")
			(net "GND")
		)
		(pad "BJ27" smd circle
			(at 1.89992 22.800056)
			(size 0.4572 0.4572)
			(layers "F.Cu" "F.Mask" "F.Paste")
			(net "P5E_PEX0_STN1_RX_DN<18>")
		)
		(pad "BJ28" smd circle
			(at 2.84988 22.800056)
			(size 0.4572 0.4572)
			(layers "F.Cu" "F.Mask" "F.Paste")
			(net "GND")
		)
		(pad "BJ29" smd circle
			(at 3.800094 22.800056)
			(size 0.4572 0.4572)
			(layers "F.Cu" "F.Mask" "F.Paste")
			(net "P5E_PEX0_STN1_RX_DN<20>")
		)
		(pad "BJ30" smd circle
			(at 4.750054 22.800056)
			(size 0.4572 0.4572)
			(layers "F.Cu" "F.Mask" "F.Paste")
			(net "GND")
		)
		(pad "BJ31" smd circle
			(at 5.700014 22.800056)
			(size 0.4572 0.4572)
			(layers "F.Cu" "F.Mask" "F.Paste")
			(net "P5E_PEX0_STN1_RX_DN<22>")
		)
		(pad "BJ32" smd circle
			(at 6.649974 22.800056)
			(size 0.4572 0.4572)
			(layers "F.Cu" "F.Mask" "F.Paste")
			(net "GND")
		)
		(pad "BJ33" smd circle
			(at 7.599934 22.800056)
			(size 0.4572 0.4572)
			(layers "F.Cu" "F.Mask" "F.Paste")
			(net "P5E_PEX0_STN1_RX_DN<24>")
		)
		(pad "BJ34" smd circle
			(at 8.549894 22.800056)
			(size 0.4572 0.4572)
			(layers "F.Cu" "F.Mask" "F.Paste")
			(net "GND")
		)
		(pad "BJ35" smd circle
			(at 9.500108 22.800056)
			(size 0.4572 0.4572)
			(layers "F.Cu" "F.Mask" "F.Paste")
			(net "P5E_PEX0_STN1_RX_DN<26>")
		)
		(pad "BJ36" smd circle
			(at 10.450068 22.800056)
			(size 0.4572 0.4572)
			(layers "F.Cu" "F.Mask" "F.Paste")
			(net "GND")
		)
		(pad "BJ37" smd circle
			(at 11.400028 22.800056)
			(size 0.4572 0.4572)
			(layers "F.Cu" "F.Mask" "F.Paste")
			(net "P5E_PEX0_STN1_RX_DN<28>")
		)
		(pad "BJ38" smd circle
			(at 12.349988 22.800056)
			(size 0.4572 0.4572)
			(layers "F.Cu" "F.Mask" "F.Paste")
			(net "GND")
		)
		(pad "BJ39" smd circle
			(at 13.299948 22.800056)
			(size 0.4572 0.4572)
			(layers "F.Cu" "F.Mask" "F.Paste")
			(net "P5E_PEX0_STN1_RX_DN<30>")
		)
		(pad "BJ40" smd circle
			(at 14.249908 22.800056)
			(size 0.4572 0.4572)
			(layers "F.Cu" "F.Mask" "F.Paste")
			(net "GND")
		)
		(pad "BJ41" smd circle
			(at 15.200122 22.800056)
			(size 0.4572 0.4572)
			(layers "F.Cu" "F.Mask" "F.Paste")
			(net "P5E_PEX0_STN0_RX_DN<15>")
		)
		(pad "BJ42" smd circle
			(at 16.150082 22.800056)
			(size 0.4572 0.4572)
			(layers "F.Cu" "F.Mask" "F.Paste")
			(net "GND")
		)
		(pad "BJ43" smd circle
			(at 17.100042 22.800056)
			(size 0.4572 0.4572)
			(layers "F.Cu" "F.Mask" "F.Paste")
			(net "P5E_PEX0_STN0_RX_DN<13>")
		)
		(pad "BJ44" smd circle
			(at 18.050002 22.800056)
			(size 0.4572 0.4572)
			(layers "F.Cu" "F.Mask" "F.Paste")
			(net "GND")
		)
		(pad "BJ45" smd circle
			(at 18.999962 22.800056)
			(size 0.4572 0.4572)
			(layers "F.Cu" "F.Mask" "F.Paste")
			(net "P5E_PEX0_STN0_RX_DN<11>")
		)
		(pad "BJ46" smd circle
			(at 19.949922 22.800056)
			(size 0.4572 0.4572)
			(layers "F.Cu" "F.Mask" "F.Paste")
			(net "GND")
		)
		(pad "BJ47" smd circle
			(at 20.899882 22.800056)
			(size 0.4572 0.4572)
			(layers "F.Cu" "F.Mask" "F.Paste")
			(net "P5E_PEX0_STN0_RX_DN<9>")
		)
		(pad "BJ48" smd circle
			(at 21.850096 22.800056)
			(size 0.4572 0.4572)
			(layers "F.Cu" "F.Mask" "F.Paste")
			(net "GND")
		)
		(pad "C1" smd circle
			(at -22.800056 -20.899882)
			(size 0.4572 0.4572)
			(layers "F.Cu" "F.Mask" "F.Paste")
			(net "P5E_PEX0_STN7_RX_DN<122>")
		)
		(pad "C2" smd circle
			(at -21.850096 -20.899882)
			(size 0.4572 0.4572)
			(layers "F.Cu" "F.Mask" "F.Paste")
			(net "P5E_PEX0_STN7_RX_DP<122>")
		)
		(pad "C3" smd circle
			(at -20.899882 -20.899882)
			(size 0.4572 0.4572)
			(layers "F.Cu" "F.Mask" "F.Paste")
			(net "GND")
		)
		(pad "C4" smd circle
			(at -19.949922 -20.899882)
			(size 0.4572 0.4572)
			(layers "F.Cu" "F.Mask" "F.Paste")
			(net "P5E_PEX0_STN7_RX_DN<124>")
		)
		(pad "C5" smd circle
			(at -18.999962 -20.899882)
			(size 0.4572 0.4572)
			(layers "F.Cu" "F.Mask" "F.Paste")
			(net "GND")
		)
		(pad "C6" smd circle
			(at -18.050002 -20.899882)
			(size 0.4572 0.4572)
			(layers "F.Cu" "F.Mask" "F.Paste")
			(net "P5E_PEX0_STN7_RX_DN<126>")
		)
		(pad "C7" smd circle
			(at -17.100042 -20.899882)
			(size 0.4572 0.4572)
			(layers "F.Cu" "F.Mask" "F.Paste")
			(net "GND")
		)
		(pad "C8" smd circle
			(at -16.150082 -20.899882)
			(size 0.4572 0.4572)
			(layers "F.Cu" "F.Mask" "F.Paste")
			(net "P5E_PEX0_STN6_RX_DN<111>")
		)
		(pad "C9" smd circle
			(at -15.200122 -20.899882)
			(size 0.4572 0.4572)
			(layers "F.Cu" "F.Mask" "F.Paste")
			(net "GND")
		)
		(pad "C10" smd circle
			(at -14.249908 -20.899882)
			(size 0.4572 0.4572)
			(layers "F.Cu" "F.Mask" "F.Paste")
			(net "P5E_PEX0_STN6_RX_DN<109>")
		)
		(pad "C11" smd circle
			(at -13.299948 -20.899882)
			(size 0.4572 0.4572)
			(layers "F.Cu" "F.Mask" "F.Paste")
			(net "GND")
		)
		(pad "C12" smd circle
			(at -12.349988 -20.899882)
			(size 0.4572 0.4572)
			(layers "F.Cu" "F.Mask" "F.Paste")
			(net "P5E_PEX0_STN6_RX_DN<107>")
		)
		(pad "C13" smd circle
			(at -11.400028 -20.899882)
			(size 0.4572 0.4572)
			(layers "F.Cu" "F.Mask" "F.Paste")
			(net "GND")
		)
		(pad "C14" smd circle
			(at -10.450068 -20.899882)
			(size 0.4572 0.4572)
			(layers "F.Cu" "F.Mask" "F.Paste")
			(net "P5E_PEX0_STN6_RX_DN<105>")
		)
		(pad "C15" smd circle
			(at -9.500108 -20.899882)
			(size 0.4572 0.4572)
			(layers "F.Cu" "F.Mask" "F.Paste")
			(net "GND")
		)
		(pad "C16" smd circle
			(at -8.549894 -20.899882)
			(size 0.4572 0.4572)
			(layers "F.Cu" "F.Mask" "F.Paste")
			(net "P5E_PEX0_STN6_RX_DN<103>")
		)
		(pad "C17" smd circle
			(at -7.599934 -20.899882)
			(size 0.4572 0.4572)
			(layers "F.Cu" "F.Mask" "F.Paste")
			(net "GND")
		)
		(pad "C18" smd circle
			(at -6.649974 -20.899882)
			(size 0.4572 0.4572)
			(layers "F.Cu" "F.Mask" "F.Paste")
			(net "P5E_PEX0_STN6_RX_DN<101>")
		)
		(pad "C19" smd circle
			(at -5.700014 -20.899882)
			(size 0.4572 0.4572)
			(layers "F.Cu" "F.Mask" "F.Paste")
			(net "GND")
		)
	)
)
